# T6G (Grand Teton) — schematic netlist excerpt (pin names and nets, part order shuffled) for the footprints in the layout excerpt that follows; sources: Cadence DE-HDL packaged netlist, KiCad conversion of 04192023_DAF0TMB3IC0_F0TG_MB_C_brd_V02_OCP.brd

PC6812  Q_CAPP  470UF 2.5V 20% SPCAP  pkg SMLF  page 363 : A = P0V9_CPU0_RT_2D ; B = GND
C1015  Q_CAP  1UF 4V 20% X6S  pkg 0201  page 312 : A = P0V9_CPU0_RT3_2A ; B = GND
R3655  Q_RES  0 5% CHIP  pkg 0402LF  page 234 : A = P3V3_AUX ; B = P3V3_AUX_USB_HUB

(kicad_pcb
	(version 20260206)
	(generator "pcbnew")
	(generator_version "10.0")
	(general
		(thickness 1.6)
		(legacy_teardrops no)
	)
	(paper "A4")
	(title_block
		(title "04192023_DAF0TMB3IC0_F0TG_MB_C_brd_V02_OCP.brd")
		(comment 1 "Grand Teton / footprints 6167-6169 of 8354")
	)
	(layers
		(0 "F.Cu" signal "TOP")
		(4 "In1.Cu" signal "GND")
		(6 "In2.Cu" signal "IN1")
		(8 "In3.Cu" signal "GND1")
		(10 "In4.Cu" signal "IN2")
		(12 "In5.Cu" signal "GND2")
		(14 "In6.Cu" signal "IN3")
		(16 "In7.Cu" signal "GND3")
		(18 "In8.Cu" signal "VCC")
		(20 "In9.Cu" signal "VCC1")
		(22 "In10.Cu" signal "GND4")
		(24 "In11.Cu" signal "IN4")
		(26 "In12.Cu" signal "GND5")
		(28 "In13.Cu" signal "IN5")
		(30 "In14.Cu" signal "GND6")
		(32 "In15.Cu" signal "IN6")
		(34 "In16.Cu" signal "GND7")
		(2 "B.Cu" signal "BOTTOM")
		(9 "F.Adhes" user "F.Adhesive")
		(11 "B.Adhes" user "B.Adhesive")
		(13 "F.Paste" user "Package Geometry/Pastemask Top")
		(15 "B.Paste" user "Package Geometry/Pastemask Bottom")
		(5 "F.SilkS" user "Ref Des/Silkscreen Top")
		(7 "B.SilkS" user "Ref Des/Silkscreen Bottom")
		(1 "F.Mask" user "Board Geometry/Soldermask Top")
		(3 "B.Mask" user "Board Geometry/Soldermask Bottom")
		(17 "Dwgs.User" user "User.Drawings")
		(19 "Cmts.User" user "User.Comments")
		(21 "Eco1.User" user "User.Eco1")
		(23 "Eco2.User" user "User.Eco2")
		(25 "Edge.Cuts" user "Board Geometry/Outline")
		(27 "Margin" user)
		(31 "F.CrtYd" user "Package Geometry/Place Bound Top")
		(29 "B.CrtYd" user "Package Geometry/Place Bound Bottom")
		(35 "F.Fab" user "Ref Des/Assembly Top")
		(33 "B.Fab" user "Ref Des/Assembly Bottom")
	)
	(footprint ""
		(layer "B.Cu")
		(at 453.921622 -390.417558 -90)
		(property "Reference" "PC6812"
			(at -0.107442 -2.997708 270)
			(unlocked yes)
			(layer "B.SilkS")
			(effects
				(font
					(size 0.7874 0.5842)
					(thickness 0.1524)
				)
				(justify left mirror)
			)
		)
		(property "Value" ""
			(at 0 0 90)
			(layer "B.Fab")
			(effects
				(font
					(size 1.27 1.27)
				)
				(justify mirror)
			)
		)
		(duplicate_pad_numbers_are_jumpers no)
		(fp_line
			(start 4.83108 2.150364)
			(end 4.447794 2.149348)
			(stroke
				(width 0.1524)
				(type default)
			)
			(layer "B.SilkS")
		)
		(fp_line
			(start -4.53898 2.15011)
			(end 4.53898 2.15011)
			(stroke
				(width 0.1524)
				(type default)
			)
			(layer "B.SilkS")
		)
		(fp_line
			(start 4.53898 2.15011)
			(end 4.53898 -2.15011)
			(stroke
				(width 0.1524)
				(type default)
			)
			(layer "B.SilkS")
		)
		(fp_line
			(start -4.53898 -2.15011)
			(end -4.53898 2.15011)
			(stroke
				(width 0.1524)
				(type default)
			)
			(layer "B.SilkS")
		)
		(fp_line
			(start 4.53898 -2.15011)
			(end -4.53898 -2.15011)
			(stroke
				(width 0.1524)
				(type default)
			)
			(layer "B.SilkS")
		)
		(fp_line
			(start 4.53898 -2.150618)
			(end 4.539742 2.152142)
			(stroke
				(width 0.1524)
				(type default)
			)
			(layer "B.SilkS")
		)
		(fp_line
			(start 4.69138 -2.150618)
			(end 4.692396 2.161032)
			(stroke
				(width 0.1524)
				(type default)
			)
			(layer "B.SilkS")
		)
		(fp_line
			(start 4.84378 -2.150618)
			(end 4.842256 2.163064)
			(stroke
				(width 0.1524)
				(type default)
			)
			(layer "B.SilkS")
		)
		(fp_line
			(start 4.84378 -2.150618)
			(end 4.53898 -2.150618)
			(stroke
				(width 0.1524)
				(type default)
			)
			(layer "B.SilkS")
		)
		(fp_line
			(start -3.64998 2.15011)
			(end 3.64998 2.15011)
			(stroke
				(width 0.1)
				(type default)
			)
			(layer "B.Fab")
		)
		(fp_line
			(start 3.64998 2.15011)
			(end 3.64998 -2.15011)
			(stroke
				(width 0.1)
				(type default)
			)
			(layer "B.Fab")
		)
		(fp_line
			(start -3.64998 -2.15011)
			(end -3.64998 2.15011)
			(stroke
				(width 0.1)
				(type default)
			)
			(layer "B.Fab")
		)
		(fp_line
			(start 3.64998 -2.15011)
			(end -3.64998 -2.15011)
			(stroke
				(width 0.1)
				(type default)
			)
			(layer "B.Fab")
		)
		(fp_text user "-"
			(at -4.585716 2.04216 270)
			(unlocked yes)
			(layer "B.SilkS")
			(effects
				(font
					(size 1.905 1.4224)
					(thickness 0.1524)
				)
				(justify left mirror)
			)
		)
		(fp_text user "+"
			(at 5.572506 -4.343908 270)
			(unlocked yes)
			(layer "B.SilkS")
			(effects
				(font
					(size 1.905 1.4224)
					(thickness 0.1524)
				)
				(justify left mirror)
			)
		)
		(fp_text user "-"
			(at -4.313174 -0.094488 270)
			(unlocked yes)
			(layer "B.Fab")
			(effects
				(font
					(size 1.905 1.4224)
					(thickness 0.1524)
				)
				(justify left mirror)
			)
		)
		(fp_text user "+"
			(at 6.214872 -0.337058 270)
			(unlocked yes)
			(layer "B.Fab")
			(effects
				(font
					(size 1.905 1.4224)
					(thickness 0.1524)
				)
				(justify left mirror)
			)
		)
		(pad "1" smd rect
			(at 3.199892 0 90)
			(size 2.413 2.8194)
			(layers "B.Cu" "B.Mask" "B.Paste")
			(net "P0V9_CPU0_RT_2D")
		)
		(pad "2" smd rect
			(at -3.199892 0 90)
			(size 2.413 2.8194)
			(layers "B.Cu" "B.Mask" "B.Paste")
			(net "GND")
		)
	)
	(footprint ""
		(layer "B.Cu")
		(at 18.838926 -97.330768 -90)
		(property "Reference" "R3655"
			(at 0 0 90)
			(layer "B.SilkS")
			(hide yes)
			(effects
				(font
					(size 1.27 1.27)
				)
				(justify mirror)
			)
		)
		(property "Value" ""
			(at 0 0 90)
			(layer "B.Fab")
			(effects
				(font
					(size 1.27 1.27)
				)
				(justify mirror)
			)
		)
		(duplicate_pad_numbers_are_jumpers no)
		(fp_line
			(start -0.7874 0.4064)
			(end 0.7874 0.4064)
			(stroke
				(width 0.1524)
				(type default)
			)
			(layer "B.SilkS")
		)
		(fp_line
			(start 0.7874 0.4064)
			(end 0.7874 -0.4064)
			(stroke
				(width 0.1524)
				(type default)
			)
			(layer "B.SilkS")
		)
		(fp_line
			(start -0.7874 -0.4064)
			(end -0.7874 0.4064)
			(stroke
				(width 0.1524)
				(type default)
			)
			(layer "B.SilkS")
		)
		(fp_line
			(start 0.7874 -0.4064)
			(end -0.7874 -0.4064)
			(stroke
				(width 0.1524)
				(type default)
			)
			(layer "B.SilkS")
		)
		(fp_line
			(start -0.67945 0.3048)
			(end -0.120396 0.3048)
			(stroke
				(width 0.1)
				(type default)
			)
			(layer "B.Fab")
		)
		(fp_line
			(start -0.120396 0.3048)
			(end -0.120396 0.2794)
			(stroke
				(width 0.1)
				(type default)
			)
			(layer "B.Fab")
		)
		(fp_line
			(start 0.12065 0.3048)
			(end 0.67945 0.3048)
			(stroke
				(width 0.1)
				(type default)
			)
			(layer "B.Fab")
		)
		(fp_line
			(start 0.67945 0.3048)
			(end 0.67945 -0.305054)
			(stroke
				(width 0.1)
				(type default)
			)
			(layer "B.Fab")
		)
		(fp_line
			(start -0.120396 0.2794)
			(end 0.12065 0.2794)
			(stroke
				(width 0.1)
				(type default)
			)
			(layer "B.Fab")
		)
		(fp_line
			(start 0.12065 0.2794)
			(end 0.12065 0.3048)
			(stroke
				(width 0.1)
				(type default)
			)
			(layer "B.Fab")
		)
		(fp_line
			(start -0.12065 -0.2794)
			(end -0.12065 -0.3048)
			(stroke
				(width 0.1)
				(type default)
			)
			(layer "B.Fab")
		)
		(fp_line
			(start 0.12065 -0.2794)
			(end -0.12065 -0.2794)
			(stroke
				(width 0.1)
				(type default)
			)
			(layer "B.Fab")
		)
		(fp_line
			(start -0.67945 -0.3048)
			(end -0.67945 0.3048)
			(stroke
				(width 0.1)
				(type default)
			)
			(layer "B.Fab")
		)
		(fp_line
			(start -0.12065 -0.3048)
			(end -0.67945 -0.3048)
			(stroke
				(width 0.1)
				(type default)
			)
			(layer "B.Fab")
		)
		(fp_line
			(start 0.12065 -0.305054)
			(end 0.12065 -0.2794)
			(stroke
				(width 0.1)
				(type default)
			)
			(layer "B.Fab")
		)
		(fp_line
			(start 0.67945 -0.305054)
			(end 0.12065 -0.305054)
			(stroke
				(width 0.1)
				(type default)
			)
			(layer "B.Fab")
		)
		(pad "1" smd circle
			(at 0.40005 0 90)
			(size 0 0)
			(layers "B.Cu" "B.Mask" "B.Paste")
			(net "P3V3_AUX")
		)
		(pad "2" smd circle
			(at -0.40005 0 90)
			(size 0 0)
			(layers "B.Cu" "B.Mask" "B.Paste")
			(net "P3V3_AUX_USB_HUB")
		)
	)
	(footprint ""
		(layer "B.Cu")
		(at 384.87858 -395.148562 90)
		(property "Reference" "C1015"
			(at 0 0 90)
			(layer "B.SilkS")
			(hide yes)
			(effects
				(font
					(size 1.27 1.27)
				)
				(justify mirror)
			)
		)
		(property "Value" ""
			(at 0 0 90)
			(layer "B.Fab")
			(effects
				(font
					(size 1.27 1.27)
				)
				(justify mirror)
			)
		)
		(duplicate_pad_numbers_are_jumpers no)
		(fp_line
			(start 0.299974 -0.150114)
			(end -0.299974 -0.150114)
			(stroke
				(width 0.1)
				(type default)
			)
			(layer "B.Fab")
		)
		(fp_line
			(start -0.299974 -0.150114)
			(end -0.299974 0.150114)
			(stroke
				(width 0.1)
				(type default)
			)
			(layer "B.Fab")
		)
		(fp_line
			(start 0.299974 0.150114)
			(end 0.299974 -0.150114)
			(stroke
				(width 0.1)
				(type default)
			)
			(layer "B.Fab")
		)
		(fp_line
			(start -0.299974 0.150114)
			(end 0.299974 0.150114)
			(stroke
				(width 0.1)
				(type default)
			)
			(layer "B.Fab")
		)
		(pad "1" smd rect
			(at 0.2667 0 270)
			(size 0.3048 0.381)
			(layers "B.Cu" "B.Mask" "B.Paste")
			(net "P0V9_CPU0_RT3_2A")
		)
		(pad "2" smd rect
			(at -0.2667 0 270)
			(size 0.3048 0.381)
			(layers "B.Cu" "B.Mask" "B.Paste")
			(net "GND")
		)
	)
)
